P  UNITS CUST 0
C   
C   IPC 356 OUTPUT.  
C
P   NNAME00000     SYS_RESET_BTN_A                                          
P   NNAME00001     SYS_RESET_BTN_B                                          
P   NNAME00002     DEBUG_HDR_A_UART_SEL                                     
P   NNAME00003     DEBUG_HDR_B_UART_SEL                                     
P   NNAME00004     SYS_RESET_BTN_B_N                                        
P   NNAME00005     SYS_RESET_BTN_A_N                                        
P   NNAME00006     UART_DEBUG_A_RX                                          
P   NNAME00007     I2C_DEBUG_A_SDA                                          
P   NNAME00008     I2C_DEBUG_A_SCL                                          
P   NNAME00009     UART_DEBUG_A_TX                                          
P   NNAME00010     I2C_DEBUG_B_SDA                                          
P   NNAME00011     UART_DEBUG_B_RX                                          
P   NNAME00012     UART_DEBUG_B_TX                                          
P   NNAME00013     I2C_DEBUG_B_SCL                                          
P   NNAME00014     UART_SEL_A_MUX_R                                         
P   NNAME00015     UART_SEL_B_MUX_R                                         
P   NNAME00016     I2C_DEBUG_B_SDA_R                                        
P   NNAME00017     I2C_DEBUG_B_SDA_L                                        
P   NNAME00018     I2C_DEBUG_B_SCL_R                                        
P   NNAME00019     I2C_DEBUG_B_SCL_L                                        
P   NNAME00020     PWR_BTN_LED_A_R                                          
P   NNAME00021     PWR_BTN_LED_B_R                                          
P   NNAME00022     SYS_RESET_BTN_A_N_R                                      
P   NNAME00023     I2C_DEBUG_A_SDA_R                                        
P   NNAME00024     I2C_DEBUG_A_SDA_L                                        
P   NNAME00025     SYS_RESET_BTN_B_N_R                                      
P   NNAME00026     I2C_DEBUG_A_SCL_L                                        
P   NNAME00027     DEBUG_CARD_A_PRSNT                                       
P   NNAME00028     DEBUG_CARD_B_PRSNT                                       
P   NNAME00029     IO_EXP_A_RESET#_FLT                                      
P   NNAME00030     IO_EXP_B_RESET#_FLT                                      
P   NNAME00031     I2C_DEBUG_A_SCL_R                                        
P   NNAME00032     DEBUG_RST_A_BTN_N                                        
P   NNAME00033     DEBUG_RST_B_BTN_N                                        
317$NONE$                       D2240PA00X+011634Y+007874               S0      
317$NONE$                       D0360PA00X+018268Y+032284               S0      
317$NONE$                       D0360PA00X+018268Y+030315               S0      
317$NONE$                       D0360PA00X+002244Y+032284               S0      
317$NONE$                       D0360PA00X+002244Y+030315               S0      
327$NONE$                             A01X+022060Y+006910X0600Y0140     S0      
327$NONE$                             A01X+022060Y+007166X0600Y0140     S0      
327$NONE$                             A01X+022060Y+007422X0600Y0140     S0      
327$NONE$                             A01X+022060Y+007678X0600Y0140     S0      
327$NONE$                             A01X+022060Y+007934X0600Y0140     S0      
327$NONE$                             A01X+022060Y+008190X0600Y0140     S0      
327$NONE$                             A01X+022060Y+008446X0600Y0140     S0      
327$NONE$                             A01X+022060Y+008702X0600Y0140     S0      
327$NONE$                             A01X+019840Y+008702X0600Y0140     S0      
327$NONE$                             A01X+019840Y+008446X0600Y0140     S0      
327$NONE$                             A01X+019840Y+008190X0600Y0140     S0      
327$NONE$                             A01X+019840Y+007934X0600Y0140     S0      
327$NONE$                             A01X+019840Y+007678X0600Y0140     S0      
327$NONE$                             A01X+019840Y+007422X0600Y0140     S0      
327$NONE$                             A01X+006950Y+007310X0600Y0140     S0      
327$NONE$                             A01X+006950Y+007566X0600Y0140     S0      
327$NONE$                             A01X+006950Y+007822X0600Y0140     S0      
327$NONE$                             A01X+006950Y+008078X0600Y0140     S0      
327$NONE$                             A01X+006950Y+008334X0600Y0140     S0      
327$NONE$                             A01X+006950Y+008590X0600Y0140     S0      
327$NONE$                             A01X+006950Y+008846X0600Y0140     S0      
327$NONE$                             A01X+006950Y+009102X0600Y0140     S0      
327$NONE$                             A01X+004730Y+009102X0600Y0140     S0      
327$NONE$                             A01X+004730Y+008846X0600Y0140     S0      
327$NONE$                             A01X+004730Y+008590X0600Y0140     S0      
327$NONE$                             A01X+004730Y+008334X0600Y0140     S0      
327$NONE$                             A01X+004730Y+008078X0600Y0140     S0      
327$NONE$                             A01X+004730Y+007822X0600Y0140     S0      
317$NONE$                       D0520PA00X+019093Y+000512               S0      
317$NONE$                       D0520PA00X+004175Y+000512               S0      
327$NONE$                             A01X+010579Y+000630X0200Y0630     S0      
317$NONE$                       D0400PA01X-000487Y+070919               S0      
317$NONE$                       D0400PA01X-000563Y+000592               S0      
317$NONE$                       D0400PA01X+001200Y+034240               S0      
317$NONE$                       D0400PA01X+018020Y+034250               S0      
317$NONE$                       D0400PA01X+021170Y+001770               S0      
317$NONE$                       D0400PA01X+048955Y+000252               S0      
327$NONE$                             A01X+002030Y+002660X2720Y2720     S0      
317$NONE$           VIA        MD0100PA01X+036661Y+057936               S0      
317$NONE$           VIA        MD0100PA04X+036661Y+057936               S0      
317$NONE$           VIA        MD0100PA01X+036552Y+038717               S0      
317$NONE$           VIA        MD0100PA04X+036552Y+038717               S0      
317$NONE$           VIA        MD0100PA01X+011558Y+071795               S0      
317$NONE$           VIA        MD0100PA04X+011558Y+071795               S0      
317$NONE$           VIA        MD0100PA01X+011450Y+052576               S0      
317$NONE$           VIA        MD0100PA04X+011450Y+052576               S0      
317$NONE$           VIA        MD0100PA01X+049482Y+071372               S0      
317$NONE$           VIA        MD0100PA04X+049482Y+071372               S0      
317$NONE$           VIA        MD0100PA01X-001751Y+072314               S0      
317$NONE$           VIA        MD0100PA04X-001751Y+072314               S0      
317$NONE$           VIA        MD0100PA01X+011558Y+032937               S0      
317$NONE$           VIA        MD0100PA04X+011558Y+032937               S0      
317$NONE$           VIA        MD0100PA01X+011450Y+013718               S0      
317$NONE$           VIA        MD0100PA04X+011450Y+013718               S0      
317$NONE$           VIA        MD0100PA01X+036552Y-000141               S0      
317$NONE$           VIA        MD0100PA04X+036552Y-000141               S0      
317$NONE$           VIA        MD0100PA01X+036661Y+019078               S0      
317$NONE$           VIA        MD0100PA04X+036661Y+019078               S0      
317$NONE$           VIA        MD0100PA01X-001890Y+001674               S0      
317$NONE$           VIA        MD0100PA04X-001890Y+001674               S0      
317$NONE$           VIA        MD0100PA01X+001380Y+006040               S0      
317$NONE$           VIA        MD0100PA04X+001380Y+006040               S0      
317$NONE$           VIA        MD0100PA01X+021880Y+033720               S0      
317$NONE$           VIA        MD0100PA04X+021880Y+033720               S0      
317$NONE$           VIA        MD0400PA04X+022200Y+000820               S0      
317P3V3_STBY_A                  D0240PA01X+004902Y+019938               S0      
317P3V3_STBY_A                  D0240PA01X+003990Y+008050               S0      
317P3V3_STBY_A                  D0240PA01X+005370Y+011830               S0      
317P3V3_STBY_A                  D0240PA01X+005970Y+003860               S0      
317P3V3_STBY_A                  D0240PA01X+005260Y+002710               S0      
317P3V3_STBY_A                  D0240PA01X+001590Y+008280               S0      
317P3V3_STBY_A                  D0240PA01X+003074Y+010354               S0      
317P3V3_STBY_A                  D0240PA01X+004020Y+005880               S0      
317P3V3_STBY_A                  D0240PA01X+004100Y+004860               S0      
317P3V3_STBY_A                  D0240PA01X+010090Y+004060               S0      
317P3V3_STBY_A                  D0220PA01X+004746Y+015417               S0      
317P3V3_STBY_A                  D0220PA01X+005449Y+018532               S0      
317P3V3_STBY_A                  D0220PA01X+004820Y+019161               S0      
317P3V3_STBY_A                  D0220PA01X+005240Y+017210               S0      
317P3V3_STBY_A                  D0220PA01X+003580Y+009140               S0      
317P3V3_STBY_A                  D0220PA01X+002820Y+012130               S0      
317P3V3_STBY_A                  D0220PA01X+002330Y+010580               S0      
317P3V3_STBY_A                  D0220PA01X+007960Y+008377               S0      
317P3V3_STBY_A                  D0220PA01X+007920Y+007350               S0      
317P3V3_STBY_A                  D0220PA01X+003353Y+006670               S0      
317P3V3_STBY_A                  D0220PA01X+007350Y+006050               S0      
317P3V3_STBY_A                  D0220PA01X+002220Y+007080               S0      
317P3V3_STBY_A                  D0220PA01X+003310Y+007080               S0      
317P3V3_STBY_A                  D0220PA01X+004144Y+010936               S0      
317P3V3_STBY_A                  D0220PA01X+001210Y+007380               S0      
317P3V3_STBY_A                  D0220PA01X+001210Y+008470               S0      
317P3V3_STBY_A                  D0220PA01X+007650Y+005460               S0      
317P3V3_STBY_A                  D0220PA01X+009807Y+004823               S0      
317P3V3_STBY_A                  D0220PA01X+009760Y+003254               S0      
327P3V3_STBY_A                        A01X+004815Y+004950X0600Y0120     S0      
327P3V3_STBY_A                        A01X+003719Y+019684X0600Y0140     S0      
327P3V3_STBY_A                        A01X+003150Y+010828X0150Y0120     S0      
327P3V3_STBY_A                        A01X+002160Y+008178X0600Y0140     S0      
327P3V3_STBY_A                        A01X+003440Y+008178X0600Y0140     S0      
327P3V3_STBY_A                        A01X+005825Y+011306X0480Y0160     S0      
327P3V3_STBY_A                        A01X+006244Y+003225X0160Y0480     S0      
327P3V3_STBY_A                        A01X+004706Y+002595X0160Y0480     S0      
327P3V3_STBY_A                        A01X+004730Y+006542X0600Y0140     S0      
327P3V3_STBY_A                        A01X+009634Y+000630X0200Y0630     S0      
327P3V3_STBY_A                        A01X+010605Y+004489X0120Y0600     S0      
317P3V3_STBY_A      VIA        MD0260PA01X+001681Y+006947               S0      
317P3V3_STBY_A      VIA        MD0100PA00X+002400Y+012090               S0      
317P3V3_STBY_A      VIA        MD0100PA00X+002720Y+010410               S0      
317P3V3_STBY_A      VIA        MD0100PA00X+003220Y+009140               S0      
317P3V3_STBY_A      VIA        MD0100PA00X+003310Y+007390               S0      
317P3V3_STBY_A      VIA        MD0100PA00X+004000Y+007710               S0      
317P3V3_STBY_A      VIA        MD0100PA00X+004149Y+010626               S0      
317P3V3_STBY_A      VIA        MD0100PA00X+004230Y+005190               S0      
317P3V3_STBY_A      VIA        MD0100PA00X+004390Y+005960               S0      
317P3V3_STBY_A      VIA        MD0100PA00X+005040Y+011830               S0      
317P3V3_STBY_A      VIA        MD0100PA00X+005140Y+016830               S0      
317P3V3_STBY_A      VIA        MD0100PA00X+005740Y+002640               S0      
317P3V3_STBY_A      VIA        MD0100PA00X+006330Y+003730               S0      
317P3V3_STBY_A      VIA        MD0100PA00X+007300Y+005720               S0      
317P3V3_STBY_A      VIA        MD0100PA00X+007960Y+008687               S0      
317P3V3_STBY_A      VIA        MD0100PA00X+007975Y+007660               S0      
317P3V3_STBY_A      VIA        MD0100PA00X+009740Y+002930               S0      
317P3V3_STBY_A      VIA        MD0100PA00X+009750Y+003660               S0      
317P3V3_STBY_A      VIA        MD0120PA00X+004410Y+015417               S0      
317P3V3_STBY_A      VIA        MD0120PA00X+005108Y+020266               S0      
317P3V3_STBY_A      VIA        MD0120PA00X+005150Y+019150               S0      
317P3V3_STBY_A      VIA        MD0160PA00X+009620Y+001640               S0      
317GND                          D0180PA01X+017874Y+028570               S0      
317GND                          D0180PA01X+000798Y+022249               S0      
317GND                          D0360PA00X+020236Y+030315               S0      
317GND                          D0360PA00X+004213Y+030315               S0      
327GND                                A01X+001663Y+012894X0610Y0510     S0      
327GND                                A01X+004793Y+012894X0610Y0510     S0      
327GND                                A01X+017687Y+012894X0610Y0510     S0      
327GND                                A01X+020817Y+012894X0610Y0510     S0      
317GND                          D0240PA01X+019776Y+005323               S0      
317GND                          D0240PA01X+018350Y+004330               S0      
317GND                          D0240PA01X+021090Y+020190               S0      
317GND                          D0240PA01X+005262Y+019938               S0      
317GND                          D0240PA01X+021840Y+011520               S0      
317GND                          D0240PA01X+016130Y+004820               S0      
317GND                          D0240PA01X+017630Y+004400               S0      
317GND                          D0240PA01X+016897Y+008703               S0      
317GND                          D0240PA01X+019272Y+007723               S0      
317GND                          D0240PA01X+003990Y+008410               S0      
317GND                          D0240PA01X+021580Y+010401               S0      
317GND                          D0240PA01X+005730Y+011830               S0      
317GND                          D0240PA01X+005610Y+003860               S0      
317GND                          D0240PA01X+005260Y+002350               S0      
317GND                          D0240PA01X+001590Y+008640               S0      
317GND                          D0240PA01X+003434Y+010354               S0      
317GND                          D0240PA01X+003660Y+005880               S0      
317GND                          D0240PA01X+003740Y+004860               S0      
317GND                          D0240PA01X+012010Y+002740               S0      
317GND                          D0240PA01X+010960Y+005180               S0      
317GND                          D0240PA01X+013260Y+005060               S0      
317GND                          D0240PA01X+010430Y+002490               S0      
317GND                          D0240PA01X+013260Y+003770               S0      
317GND                          D0240PA01X+010090Y+004420               S0      
317GND                          D0340PA01X+019565Y+028882               S0      
317GND                          D0340PA01X+019105Y+028882               S0      
317GND                          D0340PA01X+018645Y+028882               S0      
317GND                          D0340PA01X+021552Y+014070               S0      
317GND                          D0340PA01X+002240Y+015477               S0      
317GND                          D0340PA01X+000679Y+024557               S0      
317GND                          D0340PA01X+000680Y+025033               S0      
317GND                          D0340PA01X+000680Y+025508               S0      
317GND                          D0220PA01X+022068Y+004914               S0      
317GND                          D0220PA01X+022320Y+019630               S0      
317GND                          D0220PA01X+021910Y+019730               S0      
317GND                          D0220PA01X+021910Y+018130               S0      
317GND                          D0220PA01X+004820Y+019561               S0      
317GND                          D0220PA01X+004820Y+018761               S0      
317GND                          D0220PA01X+004830Y+017210               S0      
317GND                          D0220PA01X+021057Y+028345               S0      
317GND                          D0220PA01X+003030Y+028400               S0      
317GND                          D0220PA01X+021830Y+011900               S0      
317GND                          D0220PA01X+017430Y+004880               S0      
317GND                          D0220PA01X+021938Y+002591               S0      
317GND                          D0220PA01X+022250Y+003880               S0      
317GND                          D0220PA01X+019250Y+007020               S0      
317GND                          D0220PA01X+005670Y+003230               S0      
317GND                          D0220PA01X+007560Y+008377               S0      
317GND                          D0220PA01X+007920Y+006260               S0      
317GND                          D0220PA01X+003733Y+007080               S0      
317GND                          D0220PA01X+004170Y+011850               S0      
317GND                          D0220PA01X+007910Y+004700               S0      
327GND                                A01X+020715Y+003850X0600Y0120     S0      
327GND                                A01X+006445Y+004950X0600Y0120     S0      
317GND                          D0280PA00X+018858Y+022244               S0      
317GND                          D0280PA00X+002835Y+022244               S0      
327GND                                A01X+019141Y+018826X0600Y0140     S0      
327GND                                A01X+002101Y+018916X0600Y0140     S0      
327GND                                A01X+020753Y+011740X0150Y0120     S0      
327GND                                A01X+020998Y+011937X0150Y0120     S0      
327GND                                A01X+002906Y+011025X0150Y0120     S0      
327GND                                A01X+003150Y+011222X0150Y0120     S0      
327GND                                A01X+021379Y+027613X0500Y0650     S0      
327GND                                A01X+002500Y+027700X0500Y0650     S0      
327GND                                A01X+001457Y+016748X0120Y0360     S0      
327GND                                A01X+021582Y+022123X0120Y0360     S0      
327GND                                A01X+022219Y+031023X0220Y0400     S0      
327GND                                A01X+001530Y+028265X0220Y0400     S0      
327GND                                A01X+018590Y+011570X0400Y0220     S0      
327GND                                A01X+001770Y+011225X0220Y0400     S0      
327GND                                A01X+017460Y+008334X0600Y0140     S0      
327GND                                A01X+002160Y+008434X0600Y0140     S0      
327GND                                A01X+017075Y+005956X0480Y0160     S0      
327GND                                A01X+016345Y+003552X0480Y0160     S0      
327GND                                A01X+020305Y+010294X0480Y0160     S0      
327GND                                A01X+005175Y+010794X0480Y0160     S0      
327GND                                A01X+006756Y+002575X0160Y0480     S0      
327GND                                A01X+004194Y+003245X0160Y0480     S0      
327GND                                A01X+022060Y+008958X0600Y0140     S0      
327GND                                A01X+006950Y+009358X0600Y0140     S0      
327GND                                A01X+002376Y-000177X1020Y1340     S0      
327GND                                A01X+020892Y-000177X1020Y1340     S0      
327GND                                A01X+013884Y+000630X0240Y0630     S0      
327GND                                A01X+016884Y+000630X0240Y0630     S0      
327GND                                A01X+006382Y+000630X0240Y0630     S0      
327GND                                A01X+007882Y+000630X0240Y0630     S0      
327GND                                A01X+012186Y+004359X0120Y0600     S0      
327GND                                A01X+011196Y+003569X0120Y0600     S0      
317GND              VIA        MD0260PA01X+001410Y+004870               S0      
317GND              VIA        MD0260PA01X+017577Y+012164               S0      
317GND              VIA        MD0260PA01X+021908Y+002079               S0      
317GND              VIA        MD0260PA01X+022390Y+020320               S0      
317GND              VIA        MD0100PA00X+010490Y+002140               S0      
317GND              VIA        MD0100PA00X+011490Y+003990               S0      
317GND              VIA        MD0100PA00X+011810Y+004500               S0      
317GND              VIA        MD0100PA00X+011920Y+003090               S0      
317GND              VIA        MD0100PA00X+013250Y+004120               S0      
317GND              VIA        MD0100PA00X+013260Y+005380               S0      
317GND              VIA        MD0100PA00X+001365Y+027835               S0      
317GND              VIA        MD0100PA00X+001501Y+016358               S0      
317GND              VIA        MD0100PA00X+016130Y+005150               S0      
317GND              VIA        MD0100PA00X+016345Y+003235               S0      
317GND              VIA        MD0100PA00X+016975Y+006250               S0      
317GND              VIA        MD0100PA00X+001710Y+027830               S0      
317GND              VIA        MD0100PA00X+017230Y+033760               S0      
317GND              VIA        MD0100PA00X+017230Y+035020               S0      
317GND              VIA        MD0100PA00X+017280Y+004495               S0      
317GND              VIA        MD0100PA00X+017430Y+005200               S0      
317GND              VIA        MD0100PA00X+017460Y+008698               S0      
317GND              VIA        MD0100PA00X+001770Y+008940               S0      
317GND              VIA        MD0100PA00X+018280Y+004650               S0      
317GND              VIA        MD0100PA00X+018470Y+011250               S0      
317GND              VIA        MD0100PA00X+001860Y+033880               S0      
317GND              VIA        MD0100PA00X+018620Y+001490               S0      
317GND              VIA        MD0100PA00X+018800Y+035030               S0      
317GND              VIA        MD0100PA00X+018830Y+034340               S0      
317GND              VIA        MD0100PA00X+019250Y+007339               S0      
317GND              VIA        MD0100PA00X+019330Y+033790               S0      
317GND              VIA        MD0100PA00X+019456Y+005328               S0      
317GND              VIA        MD0100PA00X+019810Y+010400               S0      
317GND              VIA        MD0100PA00X+020020Y+034390               S0      
317GND              VIA        MD0100PA00X+002010Y+035030               S0      
317GND              VIA        MD0100PA00X+020330Y+001480               S0      
317GND              VIA        MD0100PA00X+020482Y+011840               S0      
317GND              VIA        MD0100PA00X+020850Y-002200               S0      
317GND              VIA        MD0100PA00X+020850Y+000940               S0      
317GND              VIA        MD0100PA00X+020950Y+035030               S0      
317GND              VIA        MD0100PA00X+021028Y+012200               S0      
317GND              VIA        MD0100PA00X+021100Y+014050               S0      
317GND              VIA        MD0100PA00X+021190Y+033750               S0      
317GND              VIA        MD0100PA00X+021412Y+021666               S0      
317GND              VIA        MD0100PA00X+021420Y+032510               S0      
317GND              VIA        MD0100PA00X+021440Y+028188               S0      
317GND              VIA        MD0100PA00X+021541Y+027050               S0      
317GND              VIA        MD0100PA00X+021780Y+001430               S0      
317GND              VIA        MD0100PA00X+021835Y+011190               S0      
317GND              VIA        MD0100PA00X+021900Y+010406               S0      
317GND              VIA        MD0100PA00X+021930Y-001390               S0      
317GND              VIA        MD0100PA00X+021990Y+033050               S0      
317GND              VIA        MD0100PA00X+022055Y+030605               S0      
317GND              VIA        MD0100PA00X+022073Y+004604               S0      
317GND              VIA        MD0100PA00X+022250Y+034450               S0      
317GND              VIA        MD0100PA00X+022250Y+003510               S0      
317GND              VIA        MD0100PA00X+022400Y+030600               S0      
317GND              VIA        MD0100PA00X+022780Y+032220               S0      
317GND              VIA        MD0100PA00X+002280Y+011260               S0      
317GND              VIA        MD0100PA00X+002282Y+028260               S0      
317GND              VIA        MD0100PA00X+022830Y+000610               S0      
317GND              VIA        MD0100PA00X+022840Y-002140               S0      
317GND              VIA        MD0100PA00X+022840Y+002280               S0      
317GND              VIA        MD0100PA00X+022840Y+035020               S0      
317GND              VIA        MD0100PA00X+022850Y+033710               S0      
317GND              VIA        MD0100PA00X+022860Y+004200               S0      
317GND              VIA        MD0100PA00X+022860Y+006920               S0      
317GND              VIA        MD0100PA00X+022860Y+008590               S0      
317GND              VIA        MD0100PA00X+002627Y+028255               S0      
317GND              VIA        MD0100PA00X+002900Y+033860               S0      
317GND              VIA        MD0100PA00X+003210Y+011490               S0      
317GND              VIA        MD0100PA00X+003320Y+005910               S0      
317GND              VIA        MD0100PA00X+003490Y+010674               S0      
317GND              VIA        MD0100PA00X+003574Y+005194               S0      
317GND              VIA        MD0100PA00X+003710Y+007396               S0      
317GND              VIA        MD0100PA00X+003750Y+008730               S0      
317GND              VIA        MD0100PA00X+000410Y+029490               S0      
317GND              VIA        MD0100PA00X+004100Y+003690               S0      
317GND              VIA        MD0100PA00X+000420Y+031210               S0      
317GND              VIA        MD0100PA00X+000420Y+032900               S0      
317GND              VIA        MD0100PA00X+004250Y+011500               S0      
317GND              VIA        MD0100PA00X+004280Y+033850               S0      
317GND              VIA        MD0100PA00X+000440Y+035030               S0      
317GND              VIA        MD0100PA00X+004400Y+035020               S0      
317GND              VIA        MD0100PA00X+004730Y+010794               S0      
317GND              VIA        MD0100PA00X+004730Y+016870               S0      
317GND              VIA        MD0100PA00X+005010Y+002070               S0      
317GND              VIA        MD0100PA00X+005550Y+004200               S0      
317GND              VIA        MD0100PA00X+005570Y+012140               S0      
317GND              VIA        MD0100PA00X+005745Y+003540               S0      
317GND              VIA        MD0100PA00X+006030Y+029000               S0      
317GND              VIA        MD0100PA00X+006030Y+033180               S0      
317GND              VIA        MD0100PA00X+006040Y+030590               S0      
317GND              VIA        MD0100PA00X+006040Y+035030               S0      
317GND              VIA        MD0100PA00X+006050Y+031640               S0      
317GND              VIA        MD0100PA00X+006945Y+004826               S0      
317GND              VIA        MD0100PA00X+007036Y+002575               S0      
317GND              VIA        MD0100PA00X+007510Y+006390               S0      
317GND              VIA        MD0100PA00X+007560Y+008700               S0      
317GND              VIA        MD0100PA00X+007560Y+009150               S0      
317GND              VIA        MD0100PA00X+007900Y+004360               S0      
317GND              VIA        MD0100PA00X+009720Y+004415               S0      
317GND              VIA        MD0120PA00X+010160Y+009970               S0      
317GND              VIA        MD0120PA00X+010200Y+006240               S0      
317GND              VIA        MD0120PA00X+011290Y+005180               S0      
317GND              VIA        MD0120PA00X+012430Y+009950               S0      
317GND              VIA        MD0120PA00X+013480Y+006030               S0      
317GND              VIA        MD0120PA00X+013580Y+007080               S0      
317GND              VIA        MD0120PA00X+013590Y+009940               S0      
317GND              VIA        MD0120PA00X+014010Y+001400               S0      
317GND              VIA        MD0120PA00X+014670Y+010840               S0      
317GND              VIA        MD0120PA00X+015470Y+011650               S0      
317GND              VIA        MD0120PA00X+001609Y-000336               S0      
317GND              VIA        MD0120PA00X+001609Y-000696               S0      
317GND              VIA        MD0120PA00X+001609Y+000024               S0      
317GND              VIA        MD0120PA00X+001609Y+000384               S0      
317GND              VIA        MD0120PA00X+016886Y+001200               S0      
317GND              VIA        MD0120PA00X+017875Y+028870               S0      
317GND              VIA        MD0120PA00X+018235Y+029215               S0      
317GND              VIA        MD0120PA00X+018610Y+018650               S0      
317GND              VIA        MD0120PA00X+019070Y+012740               S0      
317GND              VIA        MD0120PA00X+019952Y+028839               S0      
317GND              VIA        MD0120PA00X+019956Y+029202               S0      
317GND              VIA        MD0120PA00X+002020Y+011660               S0      
317GND              VIA        MD0120PA00X+020278Y+012894               S0      
317GND              VIA        MD0120PA00X+020585Y+019964               S0      
317GND              VIA        MD0120PA00X+002100Y+005350               S0      
317GND              VIA        MD0120PA00X+021229Y+003947               S0      
317GND              VIA        MD0120PA00X+021540Y+008890               S0      
317GND              VIA        MD0120PA00X+021734Y-000336               S0      
317GND              VIA        MD0120PA00X+021734Y-000696               S0      
317GND              VIA        MD0120PA00X+021734Y+000024               S0      
317GND              VIA        MD0120PA00X+021734Y+000384               S0      
317GND              VIA        MD0120PA00X+021870Y+019390               S0      
317GND              VIA        MD0120PA00X+021915Y+017800               S0      
317GND              VIA        MD0120PA00X+022245Y+019950               S0      
317GND              VIA        MD0120PA00X+002238Y+012894               S0      
317GND              VIA        MD0120PA00X+002260Y+015042               S0      
317GND              VIA        MD0120PA00X+002670Y+018916               S0      
317GND              VIA        MD0120PA00X+000410Y+001230               S0      
317GND              VIA        MD0120PA00X+004260Y+012900               S0      
317GND              VIA        MD0120PA00X+000430Y+003870               S0      
317GND              VIA        MD0120PA00X+000433Y+024201               S0      
317GND              VIA        MD0120PA00X+000463Y+006484               S0      
317GND              VIA        MD0120PA00X+005140Y+019560               S0      
317GND              VIA        MD0120PA00X+005150Y+018760               S0      
317GND              VIA        MD0120PA00X+000524Y+025911               S0      
317GND              VIA        MD0120PA00X+005676Y+019938               S0      
317GND              VIA        MD0120PA00X+000600Y-001750               S0      
317GND              VIA        MD0120PA00X+000622Y+021951               S0      
317GND              VIA        MD0120PA00X+006394Y+001158               S0      
317GND              VIA        MD0120PA00X+006560Y+012810               S0      
317GND              VIA        MD0120PA00X+007060Y+012250               S0      
317GND              VIA        MD0120PA00X+007610Y+011780               S0      
317GND              VIA        MD0120PA00X+007884Y+001160               S0      
317GND              VIA        MD0120PA00X+008163Y+011154               S0      
317GND              VIA        MD0120PA00X+008760Y+010640               S0      
317GND              VIA        MD0120PA00X+009419Y+009964               S0      
317GND              VIA        MD0120PA00X+009760Y+009220               S0      
317GND              VIA        MD0120PA00X+009800Y+006820               S0      
317P3V3_STBY_B                  D0240PA01X+019776Y+005683               S0      
317P3V3_STBY_B                  D0240PA01X+018350Y+003970               S0      
317P3V3_STBY_B                  D0240PA01X+021450Y+020190               S0      
317P3V3_STBY_B                  D0240PA01X+021480Y+011520               S0      
317P3V3_STBY_B                  D0240PA01X+016490Y+004820               S0      
317P3V3_STBY_B                  D0240PA01X+017630Y+004040               S0      
317P3V3_STBY_B                  D0240PA01X+016897Y+008343               S0      
317P3V3_STBY_B                  D0240PA01X+019272Y+008083               S0      
317P3V3_STBY_B                  D0240PA01X+021580Y+010761               S0      
317P3V3_STBY_B                  D0240PA01X+013260Y+003410               S0      
317P3V3_STBY_B                  D0220PA01X+017289Y+007014               S0      
317P3V3_STBY_B                  D0220PA01X+016894Y+007941               S0      
317P3V3_STBY_B                  D0220PA01X+020952Y+004881               S0      
317P3V3_STBY_B                  D0220PA01X+021552Y+013239               S0      
317P3V3_STBY_B                  D0220PA01X+021440Y+020670               S0      
317P3V3_STBY_B                  D0220PA01X+021910Y+018530               S0      
317P3V3_STBY_B                  D0220PA01X+022320Y+018535               S0      
317P3V3_STBY_B                  D0220PA01X+019617Y+012150               S0      
317P3V3_STBY_B                  D0220PA01X+020192Y+011360               S0      
317P3V3_STBY_B                  D0220PA01X+021883Y+012826               S0      
317P3V3_STBY_B                  D0220PA01X+017730Y+007020               S0      
317P3V3_STBY_B                  D0220PA01X+018820Y+007020               S0      
317P3V3_STBY_B                  D0220PA01X+018880Y+009000               S0      
317P3V3_STBY_B                  D0220PA01X+021538Y+002591               S0      
317P3V3_STBY_B                  D0220PA01X+021830Y+003580               S0      
317P3V3_STBY_B                  D0220PA01X+018825Y+006250               S0      
317P3V3_STBY_B                  D0220PA01X+021950Y+005320               S0      
317P3V3_STBY_B                  D0220PA01X+012000Y+002350               S0      
317P3V3_STBY_B                  D0220PA01X+013340Y+002400               S0      
327P3V3_STBY_B                        A01X+019085Y+003850X0600Y0120     S0      
327P3V3_STBY_B                        A01X+020759Y+019594X0600Y0140     S0      
327P3V3_STBY_B                        A01X+020998Y+011543X0150Y0120     S0      
327P3V3_STBY_B                        A01X+017460Y+008078X0600Y0140     S0      
327P3V3_STBY_B                        A01X+018740Y+008078X0600Y0140     S0      
327P3V3_STBY_B                        A01X+016425Y+005444X0480Y0160     S0      
327P3V3_STBY_B                        A01X+016995Y+004064X0480Y0160     S0      
327P3V3_STBY_B                        A01X+020955Y+010806X0480Y0160     S0      
327P3V3_STBY_B                        A01X+019840Y+006142X0600Y0140     S0      
327P3V3_STBY_B                        A01X+012884Y+000630X0240Y0630     S0      
327P3V3_STBY_B                        A01X+012777Y+003439X0120Y0600     S0      
317P3V3_STBY_B      VIA        MD0260PA01X+017884Y+006270               S0      
317P3V3_STBY_B      VIA        MD0100PA00X+012430Y+002260               S0      
317P3V3_STBY_B      VIA        MD0100PA00X+013260Y+002960               S0      
317P3V3_STBY_B      VIA        MD0100PA00X+016300Y+004380               S0      
317P3V3_STBY_B      VIA        MD0100PA00X+017884Y+005900               S0      
317P3V3_STBY_B      VIA        MD0100PA00X+017909Y+003819               S0      
317P3V3_STBY_B      VIA        MD0100PA00X+017950Y+004275               S0      
317P3V3_STBY_B      VIA        MD0100PA00X+018825Y+006600               S0      
317P3V3_STBY_B      VIA        MD0100PA00X+019269Y+008423               S0      
317P3V3_STBY_B      VIA        MD0100PA00X+019456Y+005678               S0      
317P3V3_STBY_B      VIA        MD0100PA00X+020729Y+004553               S0      
317P3V3_STBY_B      VIA        MD0100PA00X+021190Y+002480               S0      
317P3V3_STBY_B      VIA        MD0100PA00X+021450Y+011200               S0      
317P3V3_STBY_B      VIA        MD0100PA00X+021480Y+012831               S0      
317P3V3_STBY_B      VIA        MD0100PA00X+021830Y+003270               S0      
317P3V3_STBY_B      VIA        MD0100PA00X+021870Y+013234               S0      
317P3V3_STBY_B      VIA        MD0100PA00X+021900Y+010756               S0      
317P3V3_STBY_B      VIA        MD0100PA00X+022261Y+005315               S0      
317P3V3_STBY_B      VIA        MD0100PA00X+022400Y+021058               S0      
317P3V3_STBY_B      VIA        MD0120PA00X+022280Y+018200               S0      
317P3V3_STBY_B      VIA        MD0160PA00X+013320Y+001775               S0      
327NNAME00000                         A01X+001663Y+014665X0610Y0510     S0      
327NNAME00000                         A01X+004793Y+014665X0610Y0510     S0      
317NNAME00000                   D0340PA01X+001680Y+015477               S0      
317NNAME00000                   D0220PA01X+005086Y+015417               S0      
317NNAME00000                   D0220PA01X+002330Y+010920               S0      
327NNAME00000                         A01X+002906Y+010828X0150Y0120     S0      
327NNAME00000                         A01X+001770Y+010625X0220Y0400     S0      
317NNAME00000       VIA        MD0260PA01X+001290Y+010750               S0      
327NNAME00001                         A01X+017687Y+014665X0610Y0510     S0      
327NNAME00001                         A01X+020817Y+014665X0610Y0510     S0      
317NNAME00001                   D0340PA01X+021552Y+014630               S0      
317NNAME00001                   D0220PA01X+021552Y+013579               S0      
317NNAME00001                   D0220PA01X+019852Y+011360               S0      
327NNAME00001                         A01X+020753Y+011543X0150Y0120     S0      
327NNAME00001                         A01X+019190Y+011570X0400Y0220     S0      
317NNAME00001       VIA        MD0260PA01X+021560Y+015120               S0      
317NNAME00001       VIA        MD0100PA00X+019090Y+011220               S0      
317NNAME00001       VIA        MD0100PA00X+019350Y+013584               S0      
317USB_CONN_A_GND               D0220PA01X+003370Y+028400               S0      
317USB_CONN_A_GND               D0910PA00X+002441Y+026142               S0      
317USB_CONN_A_GND               D0910PA00X+002441Y+021102               S0      
317USB_CONN_A_GND               D0910PA00X+004016Y+026142               S0      
317USB_CONN_A_GND               D0910PA00X+004016Y+021102               S0      
327USB_CONN_A_GND                     A01X+003600Y+027700X0500Y0650     S0      
317USB_CONN_A_GND   VIA        MD0260PA01X+004393Y+027700               S0      
317USB_CONN_B_GND               D0220PA01X+020717Y+028345               S0      
317USB_CONN_B_GND               D0910PA00X+018465Y+026142               S0      
317USB_CONN_B_GND               D0910PA00X+018465Y+021102               S0      
317USB_CONN_B_GND               D0910PA00X+020039Y+026142               S0      
317USB_CONN_B_GND               D0910PA00X+020039Y+021102               S0      
327USB_CONN_B_GND                     A01X+020279Y+027613X0500Y0650     S0      
317USB_CONN_B_GND   VIA        MD0260PA01X+021376Y+024111               S0      
317P5V_USB_A                    D0340PA01X+001239Y+024557               S0      
317P5V_USB_A                    D0340PA01X+001240Y+025033               S0      
317P5V_USB_A                    D0340PA01X+001240Y+025508               S0      
327P5V_USB_A                          A01X+001110Y+023965X0550Y0450     S0      
317P5V_USB_A                    D0220PA01X+005027Y+028507               S0      
317P5V_USB_A                    D0340PA01X+003941Y+015974               S0      
327P5V_USB_A                          A01X+010884Y+000630X0240Y0630     S0      
317P5V_USB_A        VIA        MD0260PA01X+004600Y+016180               S0      
317P5V_USB_A        VIA        MD0120PA00X+005520Y+028502               S0      
317P5V_USB_A        VIA        MD0120PA00X+005640Y+015880               S0      
317P5V_USB_A        VIA        MD0160PA00X+010751Y+001672               S0      
317P5V_USB_A        VIA        MD0160PA00X+001698Y+024429               S0      
317P5V_USB_A        VIA        MD0160PA00X+001698Y+024875               S0      
317NNAME00002                   D0240PA01X+010430Y+002850               S0      
327NNAME00002                         A01X+004730Y+007566X0600Y0140     S0      
327NNAME00002                         A01X+010605Y+003569X0120Y0600     S0      
317NNAME00002       VIA        MD0260PA01X+006100Y+006050               S0      
317NNAME00002       VIA        MD0100PA00X+005870Y+005560               S0      
317NNAME00002       VIA        MD0100PA00X+009930Y+002570               S0      
317NNAME00003                   D0240PA01X+013260Y+004700               S0      
327NNAME00003                         A01X+019840Y+007166X0600Y0140     S0      
327NNAME00003                         A01X+012777Y+004359X0120Y0600     S0      
317NNAME00003       VIA        MD0260PA01X+013640Y+004650               S0      
317NNAME00003       VIA        MD0100PA00X+013644Y+003176               S0      
317NNAME00003       VIA        MD0100PA00X+020434Y+007166               S0      
317D_FLIP_CLR_A#                D0240PA01X+010600Y+005180               S0      
317D_FLIP_CLR_A#                D0220PA01X+009807Y+005163               S0      
327D_FLIP_CLR_A#                      A01X+010999Y+004489X0120Y0600     S0      
317D_FLIP_CLR_A#    VIA        MD0260PA01X+010180Y+005180               S0      
317D_FLIP_CLR_B#                D0240PA01X+011650Y+002740               S0      
317D_FLIP_CLR_B#                D0220PA01X+011660Y+002350               S0      
327D_FLIP_CLR_B#                      A01X+012383Y+003439X0120Y0600     S0      
317D_FLIP_CLR_B#    VIA        MD0260PA01X+011685Y+003410               S0      
317P5V_USB_B                    D0340PA01X+019565Y+028322               S0      
317P5V_USB_B                    D0340PA01X+019105Y+028322               S0      
317P5V_USB_B                    D0340PA01X+018645Y+028322               S0      
327P5V_USB_B                          A01X+018632Y+027648X0450Y0550     S0      
317P5V_USB_B                    D0220PA01X+022072Y+028795               S0      
317P5V_USB_B                    D0340PA01X+019438Y+015650               S0      
327P5V_USB_B                          A01X+011384Y+000630X0240Y0630     S0      
317P5V_USB_B        VIA        MD0120PA00X+019960Y+015650               S0      
317P5V_USB_B        VIA        MD0120PA00X+022068Y+028441               S0      
317P5V_USB_B        VIA        MD0160PA00X+011643Y+001657               S0      
317P5V_USB_B        VIA        MD0160PA00X+019139Y+027891               S0      
317P5V_USB_B        VIA        MD0160PA00X+019594Y+027896               S0      
317FAULT_LED_B                  D0320PA00X+019358Y+017323               S0      
327FAULT_LED_B                        A01X+011884Y+000630X0240Y0630     S0      
317FAULT_LED_B      VIA        MD0260PA01X+016521Y+011027               S0      
317PWR_LED_B_N                  D0280PA00X+017284Y+031299               S0      
327PWR_LED_B_N                        A01X+012384Y+000630X0240Y0630     S0      
317PWR_LED_B_N      VIA        MD0260PA01X+020676Y+016508               S0      
317PWR_LED_B_N      VIA        MD0100PA00X+012674Y+001566               S0      
317PWR_LED_B_N      VIA        MD0100PA00X+022020Y+015100               S0      
317NNAME00004                   D0220PA01X+018080Y+010490               S0      
327NNAME00004                         A01X+020955Y+010294X0480Y0160     S0      
327NNAME00004                         A01X+013384Y+000630X0240Y0630     S0      
317NNAME00004       VIA        MD0260PA01X+017190Y+010500               S0      
317I2C_DPB_B_SCL                D0220PA01X+020550Y+017270               S0      
327I2C_DPB_B_SCL                      A01X+014384Y+000630X0240Y0630     S0      
317I2C_DPB_B_SCL    VIA        MD0260PA01X+014588Y+005400               S0      
317I2C_DPB_B_SDA                D0220PA01X+020990Y+017270               S0      
327I2C_DPB_B_SDA                      A01X+014884Y+000630X0240Y0630     S0      
317I2C_DPB_B_SDA    VIA        MD0260PA01X+014856Y+004305               S0      
317PWR_BTN_B                    D0360PA00X+020236Y+032284               S0      
327PWR_BTN_B                          A01X+022219Y+031623X0220Y0400     S0      
327PWR_BTN_B                          A01X+015384Y+000630X0240Y0630     S0      
317PWR_BTN_B        VIA        MD0260PA01X+015134Y+006230               S0      
327UART_IOC_B_TX                      A01X+019085Y+003653X0600Y0120     S0      
327UART_IOC_B_TX                      A01X+015884Y+000630X0240Y0630     S0      
317UART_IOC_B_TX    VIA        MD0260PA01X+017233Y+002423               S0      
327UART_IOC_B_RX                      A01X+019085Y+004047X0600Y0120     S0      
327UART_IOC_B_RX                      A01X+016384Y+000630X0240Y0630     S0      
317UART_IOC_B_RX    VIA        MD0260PA01X+017239Y+001889               S0      
327UART_EXP_B_TX                      A01X+020715Y+003653X0600Y0120     S0      
327UART_EXP_B_TX                      A01X+017384Y+000630X0240Y0630     S0      
317UART_EXP_B_TX    VIA        MD0260PA01X+018117Y+002226               S0      
327UART_EXP_B_RX                      A01X+020715Y+004047X0600Y0120     S0      
327UART_EXP_B_RX                      A01X+017884Y+000630X0240Y0630     S0      
317UART_EXP_B_RX    VIA        MD0260PA01X+019371Y+002001               S0      
327UART_EXP_A_TX                      A01X+006445Y+004753X0600Y0120     S0      
327UART_EXP_A_TX                      A01X+005382Y+000630X0240Y0630     S0      
317UART_EXP_A_TX    VIA        MD0260PA01X+007340Y+003200               S0      
327UART_EXP_A_RX                      A01X+006445Y+005147X0600Y0120     S0      
327UART_EXP_A_RX                      A01X+005882Y+000630X0240Y0630     S0      
317UART_EXP_A_RX    VIA        MD0260PA01X+007717Y+002363               S0      
327UART_IOC_A_TX                      A01X+004815Y+004753X0600Y0120     S0      
327UART_IOC_A_TX                      A01X+006882Y+000630X0240Y0630     S0      
317UART_IOC_A_TX    VIA        MD0260PA01X+004130Y+004440               S0      
317UART_IOC_A_TX    VIA        MD0100PA00X+003940Y+004100               S0      
317UART_IOC_A_TX    VIA        MD0100PA00X+006884Y+001230               S0      
327UART_IOC_A_RX                      A01X+004815Y+005147X0600Y0120     S0      
327UART_IOC_A_RX                      A01X+007382Y+000630X0240Y0630     S0      
317UART_IOC_A_RX    VIA        MD0260PA01X+005180Y+003800               S0      
317UART_IOC_A_RX    VIA        MD0100PA00X+005010Y+003450               S0      
317UART_IOC_A_RX    VIA        MD0100PA00X+007384Y+001210               S0      
317PWR_BTN_A                    D0360PA00X+004213Y+032284               S0      
327PWR_BTN_A                          A01X+001530Y+028865X0220Y0400     S0      
327PWR_BTN_A                          A01X+008382Y+000630X0240Y0630     S0      
317PWR_BTN_A        VIA        MD0260PA01X+001732Y+015982               S0      
317PWR_BTN_A        VIA        MD0100PA00X+002309Y+009997               S0      
317PWR_BTN_A        VIA        MD0100PA00X+007690Y+001550               S0      
317I2C_DPB_A_SCL                D0220PA01X+000720Y+019930               S0      
327I2C_DPB_A_SCL                      A01X+008689Y+000630X0200Y0630     S0      
317I2C_DPB_A_SCL    VIA        MD0260PA01X+002704Y+009516               S0      
317I2C_DPB_A_SDA                D0220PA01X+000905Y+019180               S0      
327I2C_DPB_A_SDA                      A01X+009004Y+000630X0200Y0630     S0      
317I2C_DPB_A_SDA    VIA        MD0260PA01X+004531Y+010292               S0      
317NNAME00005                   D0220PA01X+003370Y+012150               S0      
327NNAME00005                         A01X+005825Y+010794X0480Y0160     S0      
327NNAME00005                         A01X+009319Y+000630X0200Y0630     S0      
317NNAME00005       VIA        MD0260PA01X+006915Y+010560               S0      
317PWR_LED_A_N                  D0280PA00X+001260Y+031299               S0      
327PWR_LED_A_N                        A01X+009949Y+000630X0200Y0630     S0      
317PWR_LED_A_N      VIA        MD0260PA01X+006728Y+011423               S0      
317FAULT_LED_A                  D0320PA00X+003728Y+017323               S0      
327FAULT_LED_A                        A01X+010264Y+000630X0200Y0630     S0      
317FAULT_LED_A      VIA        MD0260PA01X+005530Y+016514               S0      
317NNAME00006                   D0280PA00X+003819Y+025197               S0      
327NNAME00006                         A01X+001260Y+016748X0120Y0360     S0      
327NNAME00006                         A01X+006500Y+002575X0160Y0480     S0      
317NNAME00006       VIA        MD0260PA01X+004990Y+001635               S0      
317NNAME00006       VIA        MD0100PA00X+003690Y+001760               S0      
317NNAME00006       VIA        MD0100PA00X+000958Y+016007               S0      
317NNAME00007                   D0220PA01X+001210Y+007720               S0      
317NNAME00007                   D0280PA00X+003819Y+022835               S0      
327NNAME00007                         A01X+001654Y+016748X0120Y0360     S0      
327NNAME00007                         A01X+002160Y+007666X0600Y0140     S0      
317NNAME00007       VIA        MD0260PA01X+001617Y+007363               S0      
317NNAME00007       VIA        MD0100PA00X+002054Y+016338               S0      
317NNAME00007       VIA        MD0100PA00X+000900Y+007725               S0      
317NNAME00008                   D0220PA01X+001210Y+008130               S0      
317NNAME00008                   D0280PA00X+003819Y+022047               S0      
327NNAME00008                         A01X+001654Y+017318X0120Y0360     S0      
327NNAME00008                         A01X+002160Y+007922X0600Y0140     S0      
317NNAME00008       VIA        MD0260PA01X+001580Y+007840               S0      
317NNAME00008       VIA        MD0100PA00X+001625Y+018032               S0      
317NNAME00008       VIA        MD0100PA00X+000900Y+008125               S0      
317NNAME00009                   D0280PA00X+003819Y+024409               S0      
327NNAME00009                         A01X+001260Y+017318X0120Y0360     S0      
327NNAME00009                         A01X+004194Y+002595X0160Y0480     S0      
317NNAME00009       VIA        MD0260PA01X+003160Y+004810               S0      
317NNAME00009       VIA        MD0100PA00X+001184Y+017769               S0      
317NNAME00009       VIA        MD0100PA00X+002600Y+005160               S0      
317NNAME00010                   D0220PA01X+016949Y+007014               S0      
317NNAME00010                   D0280PA00X+019843Y+022835               S0      
327NNAME00010                         A01X+021385Y+022123X0120Y0360     S0      
327NNAME00010                         A01X+017460Y+007566X0600Y0140     S0      
317NNAME00010       VIA        MD0260PA01X+016261Y+007543               S0      
317NNAME00010       VIA        MD0100PA00X+015689Y+007938               S0      
317NNAME00010       VIA        MD0100PA00X+020775Y+022402               S0      
317NNAME00011                   D0280PA00X+019843Y+025197               S0      
327NNAME00011                         A01X+021779Y+022123X0120Y0360     S0      
327NNAME00011                         A01X+017075Y+005700X0480Y0160     S0      
317NNAME00011       VIA        MD0260PA01X+016150Y+006560               S0      
317NNAME00011       VIA        MD0100PA00X+016080Y+007200               S0      
317NNAME00011       VIA        MD0100PA00X+021927Y+021664               S0      
317NNAME00012                   D0280PA00X+019843Y+024409               S0      
327NNAME00012                         A01X+021779Y+022693X0120Y0360     S0      
327NNAME00012                         A01X+016995Y+003552X0480Y0160     S0      
317NNAME00012       VIA        MD0260PA01X+015442Y+004002               S0      
317NNAME00012       VIA        MD0100PA00X+015444Y+007204               S0      
317NNAME00012       VIA        MD0100PA00X+021592Y+023222               S0      
317NNAME00013                   D0220PA01X+016894Y+007601               S0      
317NNAME00013                   D0280PA00X+019843Y+022047               S0      
327NNAME00013                         A01X+021385Y+022693X0120Y0360     S0      
327NNAME00013                         A01X+017460Y+007822X0600Y0140     S0      
317NNAME00013       VIA        MD0260PA01X+016470Y+008230               S0      
317NNAME00013       VIA        MD0100PA00X+015971Y+008209               S0      
317NNAME00013       VIA        MD0100PA00X+020951Y+022999               S0      
317P5V_VBUS_A                   D0180PA01X+000798Y+022549               S0      
327P5V_VBUS_A                         A01X+001110Y+023205X0550Y0450     S0      
317P5V_VBUS_A                   D0280PA00X+002835Y+025000               S0      
317P5V_VBUS_A       VIA        MD0260PA01X+001164Y+022704               S0      
317P5V_VBUS_B                   D0180PA01X+017874Y+028270               S0      
327P5V_VBUS_B                         A01X+017872Y+027648X0450Y0550     S0      
317P5V_VBUS_B                   D0280PA00X+018858Y+025000               S0      
317P5V_VBUS_B       VIA        MD0260PA01X+017062Y+027180               S0      
317SYS_FAULT_A_R                D0340PA01X+003381Y+015974               S0      
317SYS_FAULT_A_R                D0320PA00X+002728Y+017323               S0      
317SYS_FAULT_A_R    VIA        MD0260PA01X+002923Y+015988               S0      
317SYS_FAULT_B_R                D0340PA01X+018878Y+015650               S0      
317SYS_FAULT_B_R                D0320PA00X+018358Y+017323               S0      
317SYS_FAULT_B_R    VIA        MD0260PA01X+018180Y+015940               S0      
317NNAME00014                   D0220PA01X+008060Y+005120               S0      
317NNAME00014                   D0220PA01X+007570Y+004700               S0      
317NNAME00014                   D0220PA01X+007650Y+005120               S0      
327NNAME00014                         A01X+006445Y+004557X0600Y0120     S0      
327NNAME00014                         A01X+006445Y+005344X0600Y0120     S0      
317NNAME00014       VIA        MD0260PA01X+007150Y+005320               S0      
317NNAME00015                   D0220PA01X+021728Y+004914               S0      
317NNAME00015                   D0220PA01X+020952Y+005221               S0      
317NNAME00015                   D0220PA01X+021530Y+005320               S0      
327NNAME00015                         A01X+020715Y+003457X0600Y0120     S0      
327NNAME00015                         A01X+020715Y+004243X0600Y0120     S0      
317NNAME00015       VIA        MD0260PA01X+021403Y+004499               S0      
317NNAME00016                   D0220PA01X+020150Y+005220               S0      
327NNAME00016                         A01X+019840Y+006398X0600Y0140     S0      
317NNAME00016       VIA        MD0260PA01X+020160Y+005710               S0      
317NNAME00017                   D0220PA01X+020150Y+004880               S0      
317NNAME00017                   D0220PA01X+018480Y+007020               S0      
327NNAME00017                         A01X+018740Y+007566X0600Y0140     S0      
317NNAME00017       VIA        MD0260PA01X+019750Y+004875               S0      
317NNAME00018                   D0220PA01X+020550Y+005220               S0      
327NNAME00018                         A01X+019840Y+006654X0600Y0140     S0      
317NNAME00018       VIA        MD0260PA01X+020570Y+005590               S0      
317NNAME00019                   D0220PA01X+020550Y+004880               S0      
317NNAME00019                   D0220PA01X+018070Y+007020               S0      
327NNAME00019                         A01X+018740Y+007822X0600Y0140     S0      
317NNAME00019       VIA        MD0260PA01X+018330Y+005470               S0      
317NNAME00020                   D0280PA00X+005197Y+031299               S0      
317NNAME00020                   D0220PA01X+005027Y+028847               S0      
317NNAME00020       VIA        MD0260PA01X+005580Y+029290               S0      
317D_FLIP_A_D                   D0220PA01X+010820Y+002490               S0      
327D_FLIP_A_D                         A01X+010802Y+003569X0120Y0600     S0      
317D_FLIP_A_D       VIA        MD0260PA01X+010830Y+002870               S0      
317D_FLIP_A_Q#                  D0220PA01X+011160Y+002490               S0      
327D_FLIP_A_Q#                        A01X+010999Y+003569X0120Y0600     S0      
317D_FLIP_A_Q#      VIA        MD0260PA01X+011260Y+002870               S0      
317D_FLIP_B_D                   D0220PA01X+012570Y+005400               S0      
327D_FLIP_B_D                         A01X+012580Y+004359X0120Y0600     S0      
317D_FLIP_B_D       VIA        MD0260PA01X+012610Y+005030               S0      
317D_FLIP_B_Q#                  D0220PA01X+012230Y+005400               S0      
327D_FLIP_B_Q#                        A01X+012383Y+004359X0120Y0600     S0      
317D_FLIP_B_Q#      VIA        MD0260PA01X+012170Y+005030               S0      
317NNAME00021                   D0280PA00X+021220Y+031299               S0      
317NNAME00021                   D0220PA01X+022072Y+029134               S0      
317NNAME00021       VIA        MD0260PA01X+022089Y+029654               S0      
317D_FLIP_PRE_A#                D0220PA01X+010100Y+003254               S0      
327D_FLIP_PRE_A#                      A01X+010802Y+004489X0120Y0600     S0      
317D_FLIP_PRE_A#    VIA        MD0260PA01X+010120Y+003650               S0      
317UART_SEL_A_MUX               D0220PA01X+008060Y+005460               S0      
327UART_SEL_A_MUX                     A01X+011196Y+004489X0120Y0600     S0      
317UART_SEL_A_MUX   VIA        MD0260PA01X+007860Y+005850               S0      
317UART_SEL_A_MUX   VIA        MD0100PA00X+010010Y+005630               S0      
317UART_SEL_A_MUX   VIA        MD0100PA00X+008220Y+006080               S0      
317D_FLIP_PRE_B#                D0220PA01X+013000Y+002400               S0      
327D_FLIP_PRE_B#                      A01X+012580Y+003439X0120Y0600     S0      
317D_FLIP_PRE_B#    VIA        MD0260PA01X+012920Y+002780               S0      
317TEMP_1_A0                    D0220PA01X+004480Y+019561               S0      
317TEMP_1_A0                    D0220PA01X+004480Y+019161               S0      
327TEMP_1_A0                          A01X+003719Y+019428X0600Y0140     S0      
317TEMP_1_A1                    D0220PA01X+005449Y+018192               S0      
317TEMP_1_A1                    D0220PA01X+004480Y+018761               S0      
327TEMP_1_A1                          A01X+003719Y+019172X0600Y0140     S0      
317TEMP_1_A1        VIA        MD0260PA01X+004932Y+018354               S0      
317TEMP_1_A2                    D0220PA01X+005240Y+017550               S0      
317TEMP_1_A2                    D0220PA01X+004830Y+017550               S0      
327TEMP_1_A2                          A01X+003719Y+018916X0600Y0140     S0      
317TEMP_1_A2        VIA        MD0260PA01X+004770Y+017963               S0      
317TEMP_1_SCL                   D0220PA01X+000720Y+020270               S0      
327TEMP_1_SCL                         A01X+002101Y+019428X0600Y0140     S0      
317TEMP_1_SCL       VIA        MD0260PA01X+001220Y+020120               S0      
317TEMP_1_SDA                   D0220PA01X+000905Y+019520               S0      
327TEMP_1_SDA                         A01X+002101Y+019684X0600Y0140     S0      
317TEMP_1_SDA       VIA        MD0260PA01X+001365Y+019525               S0      
317TEMP_2_A0                    D0220PA01X+021780Y+020670               S0      
317TEMP_2_A0                    D0220PA01X+021570Y+019730               S0      
327TEMP_2_A0                          A01X+020759Y+019338X0600Y0140     S0      
317TEMP_2_A0        VIA        MD0260PA01X+021853Y+020256               S0      
317TEMP_2_A1                    D0220PA01X+022320Y+019290               S0      
317TEMP_2_A1                    D0220PA01X+022320Y+018875               S0      
327TEMP_2_A1                          A01X+020759Y+019082X0600Y0140     S0      
317TEMP_2_A1        VIA        MD0260PA01X+021610Y+019040               S0      
317TEMP_2_A2                    D0220PA01X+021570Y+018530               S0      
317TEMP_2_A2                    D0220PA01X+021570Y+018130               S0      
327TEMP_2_A2                          A01X+020759Y+018826X0600Y0140     S0      
317TEMP_2_A2        VIA        MD0260PA01X+021190Y+018230               S0      
317TEMP_2_SCL                   D0220PA01X+020550Y+017610               S0      
327TEMP_2_SCL                         A01X+019141Y+019338X0600Y0140     S0      
317TEMP_2_SCL       VIA        MD0260PA01X+020190Y+018210               S0      
317TEMP_2_SDA                   D0220PA01X+020990Y+017610               S0      
327TEMP_2_SDA                         A01X+019141Y+019594X0600Y0140     S0      
317TEMP_2_SDA       VIA        MD0260PA01X+020740Y+018230               S0      
317RST_A_TS                     D0220PA01X+003830Y+011850               S0      
317RST_A_TS                     D0220PA01X+003804Y+010936               S0      
327RST_A_TS                           A01X+003150Y+011025X0150Y0120     S0      
317RST_A_TS         VIA        MD0260PA01X+003700Y+011330               S0      
317NNAME00022                   D0220PA01X+002820Y+011790               S0      
317NNAME00022                   D0220PA01X+003370Y+011810               S0      
327NNAME00022                         A01X+002906Y+011222X0150Y0120     S0      
327NNAME00022                         A01X+005175Y+011306X0480Y0160     S0      
317NNAME00022       VIA        MD0260PA01X+004590Y+011870               S0      
317NNAME00023                   D0220PA01X+003690Y+006260               S0      
327NNAME00023                         A01X+004730Y+006798X0600Y0140     S0      
317NNAME00023       VIA        MD0260PA01X+004130Y+006260               S0      
317NNAME00024                   D0220PA01X+002970Y+007080               S0      
317NNAME00024                   D0220PA01X+003350Y+006260               S0      
327NNAME00024                         A01X+003440Y+007666X0600Y0140     S0      
317NNAME00024       VIA        MD0260PA01X+002965Y+006650               S0      
317NNAME00025                   D0220PA01X+019277Y+012150               S0      
317NNAME00025                   D0220PA01X+018080Y+010830               S0      
327NNAME00025                         A01X+020753Y+011937X0150Y0120     S0      
327NNAME00025                         A01X+020305Y+010806X0480Y0160     S0      
317NNAME00025       VIA        MD0260PA01X+018080Y+011430               S0      
317RST_B_TS                     D0220PA01X+021490Y+011900               S0      
317RST_B_TS                     D0220PA01X+021883Y+012486               S0      
327RST_B_TS                           A01X+020998Y+011740X0150Y0120     S0      
317RST_B_TS         VIA        MD0260PA01X+021500Y+012290               S0      
317NNAME00026                   D0220PA01X+002560Y+007080               S0      
317NNAME00026                   D0220PA01X+004830Y+005970               S0      
327NNAME00026                         A01X+003440Y+007922X0600Y0140     S0      
317NNAME00026       VIA        MD0260PA01X+002940Y+005890               S0      
317NNAME00027                   D0220PA01X+005330Y+003230               S0      
317NNAME00027                   D0280PA00X+003819Y+023622               S0      
327NNAME00027                         A01X+003440Y+008434X0600Y0140     S0      
327NNAME00027                         A01X+006244Y+002575X0160Y0480     S0      
327NNAME00027                         A01X+004706Y+003245X0160Y0480     S0      
317NNAME00027       VIA        MD0260PA01X+002490Y+008960               S0      
317NNAME00027       VIA        MD0100PA00X+001586Y+020242               S0      
317NNAME00027       VIA        MD0100PA00X+001976Y+009220               S0      
317NNAME00027       VIA        MD0100PA00X+004800Y+003800               S0      
317NNAME00028                   D0220PA01X+017090Y+004880               S0      
317NNAME00028                   D0280PA00X+019843Y+023622               S0      
327NNAME00028                         A01X+018740Y+008334X0600Y0140     S0      
327NNAME00028                         A01X+017075Y+005444X0480Y0160     S0      
327NNAME00028                         A01X+016345Y+004064X0480Y0160     S0      
317NNAME00028       VIA        MD0260PA01X+018060Y+008840               S0      
317NNAME00028       VIA        MD0100PA00X+016079Y+008616               S0      
317NNAME00029                   D0220PA01X+007010Y+006050               S0      
327NNAME00029                         A01X+006950Y+006542X0600Y0140     S0      
317NNAME00029       VIA        MD0260PA01X+006620Y+006020               S0      
317TCA9555_A_A0                 D0220PA01X+004073Y+007080               S0      
317TCA9555_A_A0                 D0220PA01X+003693Y+006670               S0      
327TCA9555_A_A0                       A01X+004730Y+007310X0600Y0140     S0      
317TCA9555_A_A0     VIA        MD0260PA01X+004063Y+006710               S0      
317TCA9555_A_A1                 D0220PA01X+007920Y+006600               S0      
317TCA9555_A_A1                 D0220PA01X+007920Y+007010               S0      
327TCA9555_A_A1                       A01X+006950Y+006798X0600Y0140     S0      
317TCA9555_A_A1     VIA        MD0260PA01X+007510Y+006830               S0      
317TCA9555_A_A2                 D0220PA01X+007560Y+008037               S0      
317TCA9555_A_A2                 D0220PA01X+007960Y+008037               S0      
327TCA9555_A_A2                       A01X+006950Y+007054X0600Y0140     S0      
317TCA9555_A_A2     VIA        MD0260PA01X+007560Y+007640               S0      
317NNAME00030                   D0220PA01X+021950Y+005660               S0      
327NNAME00030                         A01X+022060Y+006142X0600Y0140     S0      
317TCA9555_B_A0                 D0220PA01X+019250Y+006680               S0      
317TCA9555_B_A0                 D0220PA01X+018825Y+005910               S0      
327TCA9555_B_A0                       A01X+019840Y+006910X0600Y0140     S0      
317TCA9555_B_A0     VIA        MD0260PA01X+019237Y+006192               S0      
317NNAME00031                   D0220PA01X+005170Y+005970               S0      
327NNAME00031                         A01X+004730Y+007054X0600Y0140     S0      
317NNAME00031       VIA        MD0260PA01X+005600Y+006050               S0      
317TCA9555_B_A1                 D0220PA01X+021830Y+003920               S0      
317TCA9555_B_A1                 D0220PA01X+022250Y+004220               S0      
327TCA9555_B_A1                       A01X+022060Y+006398X0600Y0140     S0      
317TCA9555_B_A1     VIA        MD0260PA01X+021773Y+004290               S0      
317TCA9555_B_A2                 D0220PA01X+021538Y+002930               S0      
317TCA9555_B_A2                 D0220PA01X+021938Y+002930               S0      
327TCA9555_B_A2                       A01X+022060Y+006654X0600Y0140     S0      
317TCA9555_B_A2     VIA        MD0260PA01X+022338Y+003064               S0      
317NNAME00032                   D0220PA01X+003920Y+009140               S0      
327NNAME00032                         A01X+005175Y+011050X0480Y0160     S0      
327NNAME00032                         A01X+004730Y+009358X0600Y0140     S0      
317NNAME00032       VIA        MD0260PA01X+004120Y+009510               S0      
317NNAME00032       VIA        MD0100PA00X+004090Y+008840               S0      
317NNAME00032       VIA        MD0100PA00X+004620Y+011120               S0      
317NNAME00033                   D0220PA01X+019220Y+009000               S0      
327NNAME00033                         A01X+020305Y+010550X0480Y0160     S0      
327NNAME00033                         A01X+019840Y+008958X0600Y0140     S0      
317NNAME00033       VIA        MD0260PA01X+018280Y+009210               S0      
317NNAME00033       VIA        MD0100PA00X+017126Y+009284               S0      
317NNAME00033       VIA        MD0100PA00X+018490Y+010630               S0      
317UART_SEL_B_MUX               D0220PA01X+021530Y+005660               S0      
327UART_SEL_B_MUX                     A01X+012186Y+003439X0120Y0600     S0      
317UART_SEL_B_MUX   VIA        MD0260PA01X+021130Y+005610               S0      
317UART_SEL_B_MUX   VIA        MD0100PA00X+012570Y+002650               S0      
317UART_SEL_B_MUX   VIA        MD0100PA00X+020890Y+005900               S0      
317PWR_BTN_A_CONN               D0360PA00X+003228Y+032284               S0      
317PWR_BTN_A_CONN               D0360PA00X+003228Y+030315               S0      
317PWR_BTN_B_CONN               D0360PA00X+019252Y+032284               S0      
317PWR_BTN_B_CONN               D0360PA00X+019252Y+030315               S0      
317DEBUG_USB_A_DN               D0280PA01X+001052Y+021744               S0      
317DEBUG_USB_A_DN               D0280PA00X+002835Y+024016               S0      
317DEBUG_USB_A_DP               D0280PA01X+000839Y+020786               S0      
317DEBUG_USB_A_DP               D0280PA00X+002835Y+023228               S0      
317DEBUG_USB_B_DN               D0280PA01X+017870Y+018515               S0      
317DEBUG_USB_B_DN               D0280PA00X+018858Y+024016               S0      
317DEBUG_USB_B_DP               D0280PA01X+017856Y+019701               S0      
317DEBUG_USB_B_DP               D0280PA00X+018858Y+023228               S0      
327TEMP_1_ALERT                       A01X+002101Y+019172X0600Y0140     S0      
317TEMP_1_ALERT                 D0320PA01X+001320Y+018790               S0      
327TEMP_2_ALERT                       A01X+019141Y+019082X0600Y0140     S0      
317TEMP_2_ALERT                 D0320PA01X+018365Y+019106               S0      
327UART_A_RX                          A01X+004815Y+005344X0600Y0120     S0      
327UART_A_RX                          A01X+006756Y+003225X0160Y0480     S0      
317UART_A_RX        VIA        MD0260PA01X+006730Y+003874               S0      
327UART_A_TX                          A01X+004815Y+004557X0600Y0120     S0      
327UART_A_TX                          A01X+004450Y+003245X0160Y0480     S0      
317UART_A_TX        VIA        MD0260PA01X+004442Y+003892               S0      
327UART_B_TX                          A01X+019085Y+003457X0600Y0120     S0      
327UART_B_TX                          A01X+016345Y+003808X0480Y0160     S0      
317UART_B_TX        VIA        MD0260PA01X+017764Y+003457               S0      
327UART_B_RX                          A01X+019085Y+004243X0600Y0120     S0      
327UART_B_RX                          A01X+016425Y+005956X0480Y0160     S0      
317UART_B_RX        VIA        MD0260PA01X+017870Y+005250               S0      
999
